# SCM (Grand Teton) — schematic netlist excerpt (pin names and nets, part order shuffled) for the footprints in the layout excerpt that follows; sources: Cadence DE-HDL packaged netlist, KiCad conversion of 12092022_DA0F0TMDCD0_F0T_Management_Board_D_brd_V3_OCP.brd

L22  Q_INDUCTOR4P_12  67/320MA EMPTY  pkg L_DLW21HNXA  page 29
  \1\  = USB3_01_MUX_FB_RXP
  \2\  = USB3_01_FB_RXP
  \3\  = USB3_01_FB_RXN
  \4\  = USB3_01_MUX_FB_RXN

R94  Q_RES  4.7K 1% CHIP  pkg 0402LF  page 27 : A = SPI_BMC_BOOT_MOSI ; B = GND

(kicad_pcb
	(version 20260206)
	(generator "pcbnew")
	(generator_version "10.0")
	(general
		(thickness 1.6)
		(legacy_teardrops no)
	)
	(paper "A4")
	(title_block
		(title "12092022_DA0F0TMDCD0_F0T_Management_Board_D_brd_V3_OCP.brd")
		(comment 1 "Grand Teton / footprints 675-676 of 1440")
	)
	(layers
		(0 "F.Cu" signal "TOP")
		(4 "In1.Cu" signal "GND")
		(6 "In2.Cu" signal "IN1")
		(8 "In3.Cu" signal "GND1")
		(10 "In4.Cu" signal "IN2")
		(12 "In5.Cu" signal "VCC")
		(14 "In6.Cu" signal "VCC1")
		(16 "In7.Cu" signal "IN3")
		(18 "In8.Cu" signal "GND2")
		(20 "In9.Cu" signal "IN4")
		(22 "In10.Cu" signal "GND3")
		(2 "B.Cu" signal "BOTTOM")
		(9 "F.Adhes" user "F.Adhesive")
		(11 "B.Adhes" user "B.Adhesive")
		(13 "F.Paste" user "Package Geometry/Pastemask Top")
		(15 "B.Paste" user "Package Geometry/Pastemask Bottom")
		(5 "F.SilkS" user "Ref Des/Silkscreen Top")
		(7 "B.SilkS" user "Ref Des/Silkscreen Bottom")
		(1 "F.Mask" user "Board Geometry/Soldermask Top")
		(3 "B.Mask" user "Board Geometry/Soldermask Bottom")
		(17 "Dwgs.User" user "User.Drawings")
		(19 "Cmts.User" user "User.Comments")
		(21 "Eco1.User" user "User.Eco1")
		(23 "Eco2.User" user "User.Eco2")
		(25 "Edge.Cuts" user "Board Geometry/Outline")
		(27 "Margin" user)
		(31 "F.CrtYd" user "Package Geometry/Place Bound Top")
		(29 "B.CrtYd" user "Package Geometry/Place Bound Bottom")
		(35 "F.Fab" user "Ref Des/Assembly Top")
		(33 "B.Fab" user "Ref Des/Assembly Bottom")
	)
	(footprint ""
		(layer "F.Cu")
		(at 43.45559 -22.159976)
		(property "Reference" "L22"
			(at 0 0 0)
			(layer "F.SilkS")
			(hide yes)
			(effects
				(font
					(size 1.27 1.27)
				)
			)
		)
		(property "Value" ""
			(at 0 0 0)
			(layer "F.Fab")
			(effects
				(font
					(size 1.27 1.27)
				)
			)
		)
		(duplicate_pad_numbers_are_jumpers no)
		(fp_line
			(start -0.8636 -1.524)
			(end -0.379984 -1.524)
			(stroke
				(width 0.1524)
				(type default)
			)
			(layer "F.SilkS")
		)
		(fp_line
			(start -0.8636 1.524)
			(end -0.8636 -1.524)
			(stroke
				(width 0.1524)
				(type default)
			)
			(layer "F.SilkS")
		)
		(fp_line
			(start -0.425704 1.524)
			(end -0.8636 1.524)
			(stroke
				(width 0.1524)
				(type default)
			)
			(layer "F.SilkS")
		)
		(fp_line
			(start 0.425196 -1.524)
			(end 0.8636 -1.524)
			(stroke
				(width 0.1524)
				(type default)
			)
			(layer "F.SilkS")
		)
		(fp_line
			(start 0.8636 -1.524)
			(end 0.8636 1.524)
			(stroke
				(width 0.1524)
				(type default)
			)
			(layer "F.SilkS")
		)
		(fp_line
			(start 0.8636 1.524)
			(end 0.511556 1.524)
			(stroke
				(width 0.1524)
				(type default)
			)
			(layer "F.SilkS")
		)
		(fp_poly
			(pts
				(xy -0.922528 -1.650746) (xy -1.461262 -1.830324) (xy -1.102106 -2.18948)
			)
			(stroke
				(width 0)
				(type default)
			)
			(fill yes)
			(layer "F.SilkS")
		)
		(fp_line
			(start -0.700024 -1.100074)
			(end 0.700024 -1.100074)
			(stroke
				(width 0.1)
				(type default)
			)
			(layer "F.Fab")
		)
		(fp_line
			(start -0.700024 1.100074)
			(end -0.700024 -1.100074)
			(stroke
				(width 0.1)
				(type default)
			)
			(layer "F.Fab")
		)
		(fp_line
			(start 0.700024 -1.100074)
			(end 0.700024 1.100074)
			(stroke
				(width 0.1)
				(type default)
			)
			(layer "F.Fab")
		)
		(fp_line
			(start 0.700024 1.100074)
			(end -0.700024 1.100074)
			(stroke
				(width 0.1)
				(type default)
			)
			(layer "F.Fab")
		)
		(fp_poly
			(pts
				(xy -0.4572 -1.6256) (xy -0.7112 -2.1336) (xy -0.2032 -2.1336)
			)
			(stroke
				(width 0)
				(type default)
			)
			(fill yes)
			(layer "F.Fab")
		)
		(pad "1" smd rect
			(at -0.424942 -0.849884)
			(size 0.3556 0.9144)
			(layers "F.Cu" "F.Mask" "F.Paste")
			(net "USB3_01_MUX_FB_RXP")
		)
		(pad "2" smd rect
			(at -0.424942 0.849884)
			(size 0.3556 0.9144)
			(layers "F.Cu" "F.Mask" "F.Paste")
			(net "USB3_01_FB_RXP")
		)
		(pad "3" smd rect
			(at 0.424942 0.849884)
			(size 0.3556 0.9144)
			(layers "F.Cu" "F.Mask" "F.Paste")
			(net "USB3_01_FB_RXN")
		)
		(pad "4" smd rect
			(at 0.424942 -0.849884)
			(size 0.3556 0.9144)
			(layers "F.Cu" "F.Mask" "F.Paste")
			(net "USB3_01_MUX_FB_RXN")
		)
	)
	(footprint ""
		(layer "F.Cu")
		(at 61.595 -86.868 -90)
		(property "Reference" "R94"
			(at 0 0 270)
			(layer "F.SilkS")
			(hide yes)
			(effects
				(font
					(size 1.27 1.27)
				)
			)
		)
		(property "Value" ""
			(at 0 0 270)
			(layer "F.Fab")
			(effects
				(font
					(size 1.27 1.27)
				)
			)
		)
		(duplicate_pad_numbers_are_jumpers no)
		(fp_line
			(start -0.7874 0.4064)
			(end -0.7874 -0.4064)
			(stroke
				(width 0.1524)
				(type default)
			)
			(layer "F.SilkS")
		)
		(fp_line
			(start 0.7874 0.4064)
			(end -0.7874 0.4064)
			(stroke
				(width 0.1524)
				(type default)
			)
			(layer "F.SilkS")
		)
		(fp_line
			(start -0.7874 -0.4064)
			(end 0.7874 -0.4064)
			(stroke
				(width 0.1524)
				(type default)
			)
			(layer "F.SilkS")
		)
		(fp_line
			(start 0.7874 -0.4064)
			(end 0.7874 0.4064)
			(stroke
				(width 0.1524)
				(type default)
			)
			(layer "F.SilkS")
		)
		(fp_line
			(start -0.67945 0.3048)
			(end -0.67945 -0.305054)
			(stroke
				(width 0.1)
				(type default)
			)
			(layer "F.Fab")
		)
		(fp_line
			(start -0.12065 0.3048)
			(end -0.67945 0.3048)
			(stroke
				(width 0.1)
				(type default)
			)
			(layer "F.Fab")
		)
		(fp_line
			(start 0.120396 0.3048)
			(end 0.120396 0.2794)
			(stroke
				(width 0.1)
				(type default)
			)
			(layer "F.Fab")
		)
		(fp_line
			(start 0.67945 0.3048)
			(end 0.120396 0.3048)
			(stroke
				(width 0.1)
				(type default)
			)
			(layer "F.Fab")
		)
		(fp_line
			(start -0.12065 0.2794)
			(end -0.12065 0.3048)
			(stroke
				(width 0.1)
				(type default)
			)
			(layer "F.Fab")
		)
		(fp_line
			(start 0.120396 0.2794)
			(end -0.12065 0.2794)
			(stroke
				(width 0.1)
				(type default)
			)
			(layer "F.Fab")
		)
		(fp_line
			(start -0.12065 -0.2794)
			(end 0.12065 -0.2794)
			(stroke
				(width 0.1)
				(type default)
			)
			(layer "F.Fab")
		)
		(fp_line
			(start 0.12065 -0.2794)
			(end 0.12065 -0.3048)
			(stroke
				(width 0.1)
				(type default)
			)
			(layer "F.Fab")
		)
		(fp_line
			(start 0.12065 -0.3048)
			(end 0.67945 -0.3048)
			(stroke
				(width 0.1)
				(type default)
			)
			(layer "F.Fab")
		)
		(fp_line
			(start 0.67945 -0.3048)
			(end 0.67945 0.3048)
			(stroke
				(width 0.1)
				(type default)
			)
			(layer "F.Fab")
		)
		(fp_line
			(start -0.67945 -0.305054)
			(end -0.12065 -0.305054)
			(stroke
				(width 0.1)
				(type default)
			)
			(layer "F.Fab")
		)
		(fp_line
			(start -0.12065 -0.305054)
			(end -0.12065 -0.2794)
			(stroke
				(width 0.1)
				(type default)
			)
			(layer "F.Fab")
		)
		(pad "1" smd circle
			(at -0.40005 0 270)
			(size 0 0)
			(layers "F.Cu" "F.Mask" "F.Paste")
			(net "SPI_BMC_BOOT_MOSI")
		)
		(pad "2" smd circle
			(at 0.40005 0 270)
			(size 0 0)
			(layers "F.Cu" "F.Mask" "F.Paste")
			(net "GND")
		)
	)
)
